# SCM (Grand Teton) — schematic netlist excerpt (pin names and nets, part order shuffled) for the footprints in the layout excerpt that follows; sources: Cadence DE-HDL packaged netlist, KiCad conversion of 12092022_DA0F0TMDCD0_F0T_Management_Board_D_brd_V3_OCP.brd

C280  Q_CAP  0.1UF 25V 10% X7R  pkg 0402  page 56 : A = P12V_AUX ; B = GND
C246  Q_CAP  0.01UF 50V 10% X7R  pkg C0402  page 45 : A = P3V3_AUX ; B = GND

(kicad_pcb
	(version 20260206)
	(generator "pcbnew")
	(generator_version "10.0")
	(general
		(thickness 1.6)
		(legacy_teardrops no)
	)
	(paper "A4")
	(title_block
		(title "12092022_DA0F0TMDCD0_F0T_Management_Board_D_brd_V3_OCP.brd")
		(comment 1 "Grand Teton / footprints 545-546 of 1440")
	)
	(layers
		(0 "F.Cu" signal "TOP")
		(4 "In1.Cu" signal "GND")
		(6 "In2.Cu" signal "IN1")
		(8 "In3.Cu" signal "GND1")
		(10 "In4.Cu" signal "IN2")
		(12 "In5.Cu" signal "VCC")
		(14 "In6.Cu" signal "VCC1")
		(16 "In7.Cu" signal "IN3")
		(18 "In8.Cu" signal "GND2")
		(20 "In9.Cu" signal "IN4")
		(22 "In10.Cu" signal "GND3")
		(2 "B.Cu" signal "BOTTOM")
		(9 "F.Adhes" user "F.Adhesive")
		(11 "B.Adhes" user "B.Adhesive")
		(13 "F.Paste" user "Package Geometry/Pastemask Top")
		(15 "B.Paste" user "Package Geometry/Pastemask Bottom")
		(5 "F.SilkS" user "Ref Des/Silkscreen Top")
		(7 "B.SilkS" user "Ref Des/Silkscreen Bottom")
		(1 "F.Mask" user "Board Geometry/Soldermask Top")
		(3 "B.Mask" user "Board Geometry/Soldermask Bottom")
		(17 "Dwgs.User" user "User.Drawings")
		(19 "Cmts.User" user "User.Comments")
		(21 "Eco1.User" user "User.Eco1")
		(23 "Eco2.User" user "User.Eco2")
		(25 "Edge.Cuts" user "Board Geometry/Outline")
		(27 "Margin" user)
		(31 "F.CrtYd" user "Package Geometry/Place Bound Top")
		(29 "B.CrtYd" user "Package Geometry/Place Bound Bottom")
		(35 "F.Fab" user "Ref Des/Assembly Top")
		(33 "B.Fab" user "Ref Des/Assembly Bottom")
	)
	(footprint ""
		(layer "F.Cu")
		(at 37.5666 -88.9254 -90)
		(property "Reference" "C246"
			(at 0 0 270)
			(layer "F.SilkS")
			(hide yes)
			(effects
				(font
					(size 1.27 1.27)
				)
			)
		)
		(property "Value" ""
			(at 0 0 270)
			(layer "F.Fab")
			(effects
				(font
					(size 1.27 1.27)
				)
			)
		)
		(duplicate_pad_numbers_are_jumpers no)
		(fp_line
			(start -0.7874 0.4064)
			(end -0.7874 -0.4064)
			(stroke
				(width 0.1524)
				(type default)
			)
			(layer "F.SilkS")
		)
		(fp_line
			(start 0.7874 0.4064)
			(end -0.7874 0.4064)
			(stroke
				(width 0.1524)
				(type default)
			)
			(layer "F.SilkS")
		)
		(fp_line
			(start -0.7874 -0.4064)
			(end 0.7874 -0.4064)
			(stroke
				(width 0.1524)
				(type default)
			)
			(layer "F.SilkS")
		)
		(fp_line
			(start 0.7874 -0.4064)
			(end 0.7874 0.4064)
			(stroke
				(width 0.1524)
				(type default)
			)
			(layer "F.SilkS")
		)
		(fp_line
			(start -0.67945 0.3048)
			(end -0.67945 -0.305054)
			(stroke
				(width 0.1)
				(type default)
			)
			(layer "F.Fab")
		)
		(fp_line
			(start -0.12065 0.3048)
			(end -0.67945 0.3048)
			(stroke
				(width 0.1)
				(type default)
			)
			(layer "F.Fab")
		)
		(fp_line
			(start 0.120396 0.3048)
			(end 0.120396 0.2794)
			(stroke
				(width 0.1)
				(type default)
			)
			(layer "F.Fab")
		)
		(fp_line
			(start 0.67945 0.3048)
			(end 0.120396 0.3048)
			(stroke
				(width 0.1)
				(type default)
			)
			(layer "F.Fab")
		)
		(fp_line
			(start -0.12065 0.2794)
			(end -0.12065 0.3048)
			(stroke
				(width 0.1)
				(type default)
			)
			(layer "F.Fab")
		)
		(fp_line
			(start 0.120396 0.2794)
			(end -0.12065 0.2794)
			(stroke
				(width 0.1)
				(type default)
			)
			(layer "F.Fab")
		)
		(fp_line
			(start -0.12065 -0.2794)
			(end 0.12065 -0.2794)
			(stroke
				(width 0.1)
				(type default)
			)
			(layer "F.Fab")
		)
		(fp_line
			(start 0.12065 -0.2794)
			(end 0.12065 -0.3048)
			(stroke
				(width 0.1)
				(type default)
			)
			(layer "F.Fab")
		)
		(fp_line
			(start 0.12065 -0.3048)
			(end 0.67945 -0.3048)
			(stroke
				(width 0.1)
				(type default)
			)
			(layer "F.Fab")
		)
		(fp_line
			(start 0.67945 -0.3048)
			(end 0.67945 0.3048)
			(stroke
				(width 0.1)
				(type default)
			)
			(layer "F.Fab")
		)
		(fp_line
			(start -0.67945 -0.305054)
			(end -0.12065 -0.305054)
			(stroke
				(width 0.1)
				(type default)
			)
			(layer "F.Fab")
		)
		(fp_line
			(start -0.12065 -0.305054)
			(end -0.12065 -0.2794)
			(stroke
				(width 0.1)
				(type default)
			)
			(layer "F.Fab")
		)
		(pad "1" smd circle
			(at -0.40005 0 270)
			(size 0 0)
			(layers "F.Cu" "F.Mask" "F.Paste")
			(net "P3V3_AUX")
		)
		(pad "2" smd circle
			(at 0.40005 0 270)
			(size 0 0)
			(layers "F.Cu" "F.Mask" "F.Paste")
			(net "GND")
		)
	)
	(footprint ""
		(layer "F.Cu")
		(at 19.177 -39.751 -90)
		(property "Reference" "C280"
			(at 0 0 270)
			(layer "F.SilkS")
			(hide yes)
			(effects
				(font
					(size 1.27 1.27)
				)
			)
		)
		(property "Value" ""
			(at 0 0 270)
			(layer "F.Fab")
			(effects
				(font
					(size 1.27 1.27)
				)
			)
		)
		(duplicate_pad_numbers_are_jumpers no)
		(fp_line
			(start -0.7874 0.4064)
			(end -0.7874 -0.4064)
			(stroke
				(width 0.1524)
				(type default)
			)
			(layer "F.SilkS")
		)
		(fp_line
			(start 0.7874 0.4064)
			(end -0.7874 0.4064)
			(stroke
				(width 0.1524)
				(type default)
			)
			(layer "F.SilkS")
		)
		(fp_line
			(start -0.7874 -0.4064)
			(end 0.7874 -0.4064)
			(stroke
				(width 0.1524)
				(type default)
			)
			(layer "F.SilkS")
		)
		(fp_line
			(start 0.7874 -0.4064)
			(end 0.7874 0.4064)
			(stroke
				(width 0.1524)
				(type default)
			)
			(layer "F.SilkS")
		)
		(fp_line
			(start -0.67945 0.3048)
			(end -0.67945 -0.305054)
			(stroke
				(width 0.1)
				(type default)
			)
			(layer "F.Fab")
		)
		(fp_line
			(start -0.12065 0.3048)
			(end -0.67945 0.3048)
			(stroke
				(width 0.1)
				(type default)
			)
			(layer "F.Fab")
		)
		(fp_line
			(start 0.120396 0.3048)
			(end 0.120396 0.2794)
			(stroke
				(width 0.1)
				(type default)
			)
			(layer "F.Fab")
		)
		(fp_line
			(start 0.67945 0.3048)
			(end 0.120396 0.3048)
			(stroke
				(width 0.1)
				(type default)
			)
			(layer "F.Fab")
		)
		(fp_line
			(start -0.12065 0.2794)
			(end -0.12065 0.3048)
			(stroke
				(width 0.1)
				(type default)
			)
			(layer "F.Fab")
		)
		(fp_line
			(start 0.120396 0.2794)
			(end -0.12065 0.2794)
			(stroke
				(width 0.1)
				(type default)
			)
			(layer "F.Fab")
		)
		(fp_line
			(start -0.12065 -0.2794)
			(end 0.12065 -0.2794)
			(stroke
				(width 0.1)
				(type default)
			)
			(layer "F.Fab")
		)
		(fp_line
			(start 0.12065 -0.2794)
			(end 0.12065 -0.3048)
			(stroke
				(width 0.1)
				(type default)
			)
			(layer "F.Fab")
		)
		(fp_line
			(start 0.12065 -0.3048)
			(end 0.67945 -0.3048)
			(stroke
				(width 0.1)
				(type default)
			)
			(layer "F.Fab")
		)
		(fp_line
			(start 0.67945 -0.3048)
			(end 0.67945 0.3048)
			(stroke
				(width 0.1)
				(type default)
			)
			(layer "F.Fab")
		)
		(fp_line
			(start -0.67945 -0.305054)
			(end -0.12065 -0.305054)
			(stroke
				(width 0.1)
				(type default)
			)
			(layer "F.Fab")
		)
		(fp_line
			(start -0.12065 -0.305054)
			(end -0.12065 -0.2794)
			(stroke
				(width 0.1)
				(type default)
			)
			(layer "F.Fab")
		)
		(pad "1" smd circle
			(at -0.40005 0 270)
			(size 0 0)
			(layers "F.Cu" "F.Mask" "F.Paste")
			(net "P12V_AUX")
		)
		(pad "2" smd circle
			(at 0.40005 0 270)
			(size 0 0)
			(layers "F.Cu" "F.Mask" "F.Paste")
			(net "GND")
		)
	)
)
